FILE_TYPE = CONNECTIVITY;
{Allegro Design Entry HDL 17.2-2016 S081 (4005846) 1/11/2022}
"PAGE_NUMBER" = 13;
0"NC";
1"P3V3_AUX\g";
2"P3V3_P2V5_P1V8_RVDD\g";
3"P3V3_AUX\g";
4"P2V5_AUX\g";
5"P1V8_AUX\g";
6"P3V3_LDO\g";
7"P3V3_AUX\g";
8"P3V3_AUX\g";
9"P3V3_AUX\g";
10"GND\g";
11"GND\g";
12"GND\g";
13"GND\g";
14"PD_CLK_125M_PHY_BMC_RGMII";
15"CLK_BUF1_GPU_FPGA_OE_R_N";
16"FM_BIC_DEBUG_SW_N_R";
17"GPU_FPGA_RST_N";
18"FM_JTAG_SEL";
19"RMII_CSRDV";
20"RMII_RXD1";
21"FM_PLT_BMC_THERMTRIP_N_R";
22"UART_BMC_1_RXD";
23"UART_BMC_1_TXD";
24"FM_DBP_BMC_PRDY_R_N";
25"PWRGD_PSU_AC_PWROK_BMC";
26"LED_POSTCODE_2";
27"LED_POSTCODE_3";
28"UART_BMC_5_RXD_R";
29"UART_BMC_5_TXD_R";
30"IRQ_SML0_ALERT_R_N";
31"RMII_TXEN_R";
32"RMII_TXD0_R";
33"RMII_TXD1_R";
34"FM_BIOS_DEBUG_EN_R_N";
35"RST_PLTRST_R_N";
36"FM_BIOS_DEBUG_EN_N";
37"PD_BIOS_MUX_EN_N";
38"RMII_TXD1";
39"RMII_TXD0";
40"RMII_TXEN";
41"FM_CPU_RMCA_CATERR_LVT3_R_N";
42"FM_BMC_CPU_FBRK_OUT_N";
43"RST_SGPIO_RESET_BMC_N";
44"RST_ROT_CPU_R1_N";
45"H_CPU_CATERR_LVC2_R2_N";
46"IRQ_BMC_PCH_NMI_N";
47"BMC_MONITER";
48"BMC_ID_BEEP_SEL_R1";
49"FM_SLPS3_GF_R1_N";
50"IRQ_BMC_CPU_NMI";
51"FM_ID_LED";
52"SMB_BMC_ALERT4_R_N";
53"FM_ME_BT_DONE";
54"PU_SPI1WP_N";
55"FM_CPU_MSMI_CATERR_LVT3_N";
56"RST_SGPIO_RESET_N";
57"RST_ROT_CPU_N";
58"PU_FWSPIWP_N";
59"PU_BMC_FWSPIABR_N";
60"SPI_BMC_TPM_CS2_R_N";
61"IRQ_PCH_SCI_WHEA_N";
62"FM_BMC_ONCTL_R_N";
63"PU_SPI1WP_N";
64"FM_BMC_SUSACK_N";
65"FM_SLPS3_GF_N";
66"IRQ_BMC_PCH_NMI_N";
67"FM_BMC_CPU_FBRK_OUT_R_N";
68"PU_SPI1ABR";
69"FM_BMC_READY_R_PLD_N";
70"IRQ_PCH_SCI_WHEA_R_N";
71"FLASH_WP_STATUS_R1";
72"IRQ_TPM_SPI_N";
73"FM_BMC_SUSACK_R1_N";
74"H_CPU1_PROCHOT_LVC1_R_N";
75"FM_BMC_DEBUG_SW_N";
76"VOL_SEN_ALERT_R";
77"FM_PECI_SEL_R_N";
78"FM_VIRTUAL_RESEAT_BMC";
79"FM_THROTTLE_N";
80"FM_BMC_ONCTL_R_N";
81"FM_ESPI_PLD_R1_EN";
82"SPI_BMC_IO3_R";
83"SPI_BMC_IO2_R";
84"FM_DEBUG_PORT_PRSNT_R1_N";
85"SPI_BMC_BIOS_ROM_CLK";
86"SPI_BMC_BIOS_ROM_MOSI";
87"SPI_BMC_BIOS_ROM_IO3";
88"FM_BMC_MUX_CS_SPI_SEL_0";
89"SPI_BMC_BIOS_ROM_MISO";
90"RST_WDTRST_PLD_R1_N";
91"PD_BIOS_MUX_EN_R_N";
92"LED_POSTCODE_7";
93"LED_POSTCODE_6";
94"LED_POSTCODE_5";
95"LED_POSTCODE_4";
96"BATTERY_DETECT";
97"BMC_EMMC_RST_N";
98"FM_FLASH_LATCH_N";
99"RST_WDTRST_PLD_N";
100"RST_BMC_SELF_HW";
101"BMC_CPLD_GPIO_2";
102"RST_PCA9548_SENSOR_N";
103"LED_POSTCODE_1";
104"LED_POSTCODE_0";
105"BMC_EMMC_RST_R_N";
106"FM_FLASH_LATCH_N_R1";
107"SPI_BMC_MISO_IO1_R";
108"SPI_BMC_TPM_CLK_R1";
109"SPI_BMC_BIOS_ROM_IO2";
110"H_CPU1_PROCHOT_LVC1_N";
111"RST_PCA9548_SENSOR_R_N";
112"BMC_CPLD_GPIO_2_R1";
113"SPI_BMC_BOOT_CLK";
114"SPI_BMC_MOSI_IO0_R";
115"SPI_BMC_TPM_MOSI_R1";
116"PU_FWSPIWP_N_R";
117"PU_FWSPIWP_N";
118"BMC_HEARTBEAT_R_N";
119"IRQ_SGPIO_N";
120"CLK_GEN2_BMC_RC_OE_N";
121"SPI_BMC_TPM_MOSI";
122"SPI_BMC_TPM_CLK";
123"SPI_BMC_BOOT_MOSI";
124"RMII_OCP_RCLKI_ISO";
125"IRQ_BMC_CPU_NMI_R";
126"SMB_BMC_ALERT3_R_N";
127"FM_DEBUG_PORT_PRSNT_N";
128"SPI_BMC_TPM_MISO";
129"QSPI_2_PLD_IO3";
130"QSPI_2_PLD_IO2";
131"QSPI_2_PLD_CLK";
132"FM_BMC_CRASHLOG_TRIG_N";
133"FM_BIC_DEBUG_SW_N";
134"IRQ_SGPIO_BMC_N";
135"PU_SPI1ABR";
136"SPI_BMC_BOOT_CS0_R_N";
137"RMII_OCP_RCLKI";
138"PWRGD_P1V0_AUX_DELAY_R";
139"PWRGD_P1V0_AUX_DELAY";
140"PU_BMC_FWSPIABR_N";
141"SPI_BMC_TPM_CS2_R_N";
142"PWRGD_DSW_PWROK";
143"IRQ_SMI_ACTIVE_GF_N";
144"SMB_BMC_ALERT3_N";
145"FM_ESPI_PLD_EN";
146"PWRGD_SYS_PWROK_BMC";
147"FM_DBP_CPU_PREQ_GF_N";
148"FM_JTAG_TCK_MUX_BMC_SEL_R1";
149"RMII_OCP_RCLKI_R_ISO";
150"RMII_RXD0";
151"RMII_RXER";
152"FM_BMC_CRASHLOG_TRIG_R1_N";
153"FM_VIRTUAL_RESEAT";
154"BMC_ID_BEEP_SEL";
155"RMII_OCP_RCLKI_R_ISO";
156"SPI_BMC_BOOT_CS1_R_N";
157"IRQ_SMI_ACTIVE_BMC_N";
158"PWRGD_DSW_PWROK_R1";
159"SPI_BMC_BIOS_CS0_R1_N";
160"SPI_BMC_TPM_CS2_R1_N";
161"TP_BMC_SPICS0_N";
162"SPI_BMC_BOOT_CS1_R1_N";
163"SPI_BMC_CLK_R";
164"SPI_BMC_BOOT_MISO";
165"QSPI_2_PLD_IO1";
166"QSPI_2_PLD_IO0";
167"IRQ_PCH_SCI_WHEA_N";
168"FLASH_WP_STATUS";
169"FM_BMC_SUSACK_N";
170"FM_BMC_READY_PLD_N";
171"SPI_BMC_TPM_MISO_R1";
172"RST_BMC_SELF_HW_R1";
173"H_CPU0_PROCHOT_LVC1_N";
174"RST_RSMRST_R_N";
175"SPI_BMC_BOOT_CS0_R1_N";
176"TP_BMC_SPICS2_N";
177"PU_BMC_FWSPIABR_N_R";
178"SMB_BMC_ALERT4_N";
179"FM_SLPS3_GF_N";
180"SPI_BMC_BIOS_CS0_N";
181"UART_BMC_5_RXD";
182"UART_BMC_5_TXD";
183"BMC_HEARTBEAT_N";
184"RST_RSMRST_N";
185"PWRGD_PSU_AC_PWROK";
186"FM_PECI_SEL_N";
187"PWRGD_SYS_PWROK";
188"FM_DBP_BMC_PRDY_N";
189"UART_BMC_1_TXD_R";
190"UART_BMC_1_RXD_R";
191"FM_JTAG_TCK_MUX_BMC_SEL";
192"FM_PCH_BMC_THERMTRIP_N";
193"FM_DBP_CPU_PREQ_GF_R_N";
194"FM_BMC_READY_R_PLD_N";
195"FM_BIOS_DEBUG_EN_R_N";
196"RST_WDTRST_PLD_N";
197"FM_PECI_SEL_N";
%"UNIVERSAL_POWER"
"1","(-3450,-500)","0","logical_power","I1";
;
HDL_POWER"P1V8_AUX"
CDS_LIB"logical_power";
"A"5;
%"Q_RES"
"1","(-1825,3625)","0","pure_quanta","I133";
;
MATERIAL"CHIP"
VALUE"33.2"
CDS_LIB"pure_quanta"
WATTAGE"1/16W"
PACK_TYPE"0402LF"
PART_NUMBER"CS03322FB03"
TOLERANCE"1%"
LOCATION"R37"
$SEC"1"
CDS_SEC"1";
"B"
$PN"2"157;
"A"
$PN"1"143;
%"Q_RES"
"1","(-2125,2225)","0","pure_quanta","I156";
;
MATERIAL"CHIP"
VALUE"33.2"
TOLERANCE"1%"
PART_NUMBER"CS03322FB03"
PACK_TYPE"0402LF"
WATTAGE"1/16W"
CDS_LIB"pure_quanta"
LOCATION"R237"
$SEC"1"
CDS_SEC"1";
"B"
$PN"2"24;
"A"
$PN"1"188;
%"Q_RES"
"1","(-1775,2825)","0","pure_quanta","I159";
;
MATERIAL"CHIP"
VALUE"33.2"
TOLERANCE"1%"
PART_NUMBER"CS03322FB03"
PACK_TYPE"0402LF"
WATTAGE"1/16W"
CDS_LIB"pure_quanta"
LOCATION"R160"
$SEC"1"
CDS_SEC"1";
"B"
$PN"2"174;
"A"
$PN"1"184;
%"Q_RES"
"1","(-2125,2025)","0","pure_quanta","I16";
;
MATERIAL"CHIP"
VALUE"33.2"
TOLERANCE"1%"
PART_NUMBER"CS03322FB03"
PACK_TYPE"0402LF"
WATTAGE"1/16W"
CDS_LIB"pure_quanta"
LOCATION"R158"
$SEC"1"
CDS_SEC"1";
"B"
$PN"2"147;
"A"
$PN"1"193;
%"Q_RES"
"1","(-2125,1975)","0","pure_quanta","I17";
;
VALUE"33.2"
MATERIAL"CHIP"
TOLERANCE"1%"
PART_NUMBER"CS03322FB03"
PACK_TYPE"0402LF"
WATTAGE"1/16W"
CDS_LIB"pure_quanta"
LOCATION"R159"
$SEC"1"
CDS_SEC"1";
"B"
$PN"2"148;
"A"
$PN"1"191;
%"Q_RES"
"1","(-2125,2175)","0","pure_quanta","I18";
;
MATERIAL"CHIP"
VALUE"33.2"
TOLERANCE"1%"
PART_NUMBER"CS03322FB03"
PACK_TYPE"0402LF"
WATTAGE"1/16W"
CDS_LIB"pure_quanta"
LOCATION"R157"
$SEC"1"
CDS_SEC"1";
"B"
$PN"2"23;
"A"
$PN"1"189;
%"Q_RES"
"1","(2750,375)","0","pure_quanta","I184";
;
MATERIAL"CHIP"
VALUE"4.7K"
PART_NUMBER"CS24702FB06"
PACK_TYPE"0402LF"
WATTAGE"1/16W"
TOLERANCE"1%"
CDS_LIB"pure_quanta"
LOCATION"R238"
$SEC"1"
CDS_SEC"1";
"B"
$PN"2"60;
"A"
$PN"1"8;
%"Q_RES"
"1","(2750,325)","0","pure_quanta","I185";
;
MATERIAL"CHIP"
VALUE"4.7K"
PART_NUMBER"CS24702FB06"
PACK_TYPE"0402LF"
WATTAGE"1/16W"
TOLERANCE"1%"
CDS_LIB"pure_quanta"
LOCATION"R239"
$SEC"1"
CDS_SEC"1";
"B"
$PN"2"59;
"A"
$PN"1"8;
%"Q_RES"
"1","(2750,225)","0","pure_quanta","I186";
;
MATERIAL"CHIP"
VALUE"4.7K"
PART_NUMBER"CS24702FB06"
PACK_TYPE"0402LF"
WATTAGE"1/16W"
TOLERANCE"1%"
CDS_LIB"pure_quanta"
LOCATION"R241"
$SEC"1"
CDS_SEC"1";
"B"
$PN"2"68;
"A"
$PN"1"8;
%"Q_RES"
"1","(2750,275)","0","pure_quanta","I187";
;
MATERIAL"CHIP"
VALUE"4.7K"
PART_NUMBER"CS24702FB06"
PACK_TYPE"0402LF"
WATTAGE"1/16W"
TOLERANCE"1%"
CDS_LIB"pure_quanta"
LOCATION"R240"
$SEC"1"
CDS_SEC"1";
"B"
$PN"2"58;
"A"
$PN"1"8;
%"Q_RES"
"1","(2750,175)","0","pure_quanta","I188";
;
VALUE"4.7K"
MATERIAL"CHIP"
PART_NUMBER"CS24702FB06"
PACK_TYPE"0402LF"
WATTAGE"1/16W"
TOLERANCE"1%"
CDS_LIB"pure_quanta"
LOCATION"R683"
$SEC"1"
CDS_SEC"1";
"B"
$PN"2"63;
"A"
$PN"1"8;
%"UNIVERSAL_POWER"
"1","(2425,625)","0","logical_power","I194";
;
HDL_POWER"P3V3_AUX"
CDS_LIB"logical_power";
"A"8;
%"Q_RES"
"1","(-2125,2125)","0","pure_quanta","I198";
;
MATERIAL"CHIP"
VALUE"33.2"
TOLERANCE"1%"
PART_NUMBER"CS03322FB03"
PACK_TYPE"0402LF"
WATTAGE"1/16W"
CDS_LIB"pure_quanta"
LOCATION"R427"
$SEC"1"
CDS_SEC"1";
"B"
$PN"2"22;
"A"
$PN"1"190;
%"UNIVERSAL_POWER"
"1","(-3375,-150)","0","logical_power","I2";
;
HDL_POWER"P2V5_AUX"
CDS_LIB"logical_power";
"A"4;
%"Q_RES"
"1","(2750,75)","0","pure_quanta","I200";
;
VALUE"4.7K"
MATERIAL"CHIP"
PART_NUMBER"CS24702FB06"
PACK_TYPE"0402LF"
WATTAGE"1/16W"
CDS_LIB"pure_quanta"
TOLERANCE"1%"
LOCATION"R38"
$SEC"1"
CDS_SEC"1";
"B"
$PN"2"64;
"A"
$PN"1"8;
%"Q_RES"
"1","(2750,25)","0","pure_quanta","I204";
;
VALUE"4.7K"
MATERIAL"CHIP"
PART_NUMBER"CS24702FB06"
PACK_TYPE"0402LF"
WATTAGE"1/16W"
TOLERANCE"1%"
CDS_LIB"pure_quanta"
LOCATION"R61"
$SEC"1"
CDS_SEC"1";
"B"
$PN"2"66;
"A"
$PN"1"8;
%"Q_RES"
"1","(2875,1975)","0","pure_quanta","I208";
;
VALUE"33.2"
MATERIAL"CHIP"
TOLERANCE"1%"
PART_NUMBER"CS03322FB03"
PACK_TYPE"0402LF"
WATTAGE"1/16W"
CDS_LIB"pure_quanta"
LOCATION"R759"
$SEC"1"
CDS_SEC"1";
"B"
$PN"2"28;
"A"
$PN"1"181;
%"Q_RES"
"1","(2750,-25)","0","pure_quanta","I213";
;
VALUE"4.7K"
MATERIAL"CHIP"
PART_NUMBER"CS24702FB06"
PACK_TYPE"0402LF"
WATTAGE"1/16W"
TOLERANCE"1%"
CDS_LIB"pure_quanta"
LOCATION"R774"
$SEC"1"
CDS_SEC"1";
"B"
$PN"2"65;
"A"
$PN"1"8;
%"Q_RES"
"1","(-1825,3725)","0","pure_quanta","I215";
;
VALUE"33.2"
MATERIAL"CHIP"
TOLERANCE"1%"
PART_NUMBER"CS03322FB03"
PACK_TYPE"0402LF"
WATTAGE"1/16W"
CDS_LIB"pure_quanta"
LOCATION"R799"
$SEC"1"
CDS_SEC"1";
"B"
$PN"2"159;
"A"
$PN"1"180;
%"Q_RES"
"1","(-1775,4325)","0","pure_quanta","I217";
;
MATERIAL"CHIP"
VALUE"33.2"
WATTAGE"1/16W"
PACK_TYPE"0402LF"
PART_NUMBER"CS03322FB03"
TOLERANCE"1%"
CDS_LIB"pure_quanta"
LOCATION"R801"
$SEC"1"
CDS_SEC"1";
"B"
$PN"2"175;
"A"
$PN"1"136;
%"Q_RES"
"1","(-1775,4275)","0","pure_quanta","I218";
;
MATERIAL"CHIP"
VALUE"33.2"
WATTAGE"1/16W"
PACK_TYPE"0402LF"
PART_NUMBER"CS03322FB03"
TOLERANCE"1%"
CDS_LIB"pure_quanta"
LOCATION"R802"
$SEC"1"
CDS_SEC"1";
"B"
$PN"2"162;
"A"
$PN"1"156;
%"Q_RES"
"1","(2750,-75)","0","pure_quanta","I220";
;
VALUE"4.7K"
MATERIAL"EMPTY"
PART_NUMBER"CS24702FB06"
PACK_TYPE"0402LF"
WATTAGE"1/16W"
TOLERANCE"1%"
CDS_LIB"pure_quanta"
LOCATION"R821"
$SEC"1"
CDS_SEC"1";
"B"
$PN"2"62;
"A"
$PN"1"8;
%"Q_RES"
"1","(-2300,2425)","0","pure_quanta","I223";
;
VALUE"33.2"
MATERIAL"CHIP"
TOLERANCE"1%"
PART_NUMBER"CS03322FB03"
PACK_TYPE"0402LF"
WATTAGE"1/16W"
CDS_LIB"pure_quanta"
LOCATION"R824"
$SEC"1"
CDS_SEC"1";
"B"
$PN"2"78;
"A"
$PN"1"153;
%"Q_RES"
"1","(-2300,2375)","0","pure_quanta","I225";
;
MATERIAL"CHIP"
VALUE"33.2"
TOLERANCE"1%"
PART_NUMBER"CS03322FB03"
PACK_TYPE"0402LF"
WATTAGE"1/16W"
CDS_LIB"pure_quanta"
LOCATION"R836"
$SEC"1"
CDS_SEC"1";
"B"
$PN"2"25;
"A"
$PN"1"185;
%"Q_RES"
"1","(-2300,2325)","0","pure_quanta","I227";
;
VALUE"33.2"
MATERIAL"CHIP"
TOLERANCE"1%"
PART_NUMBER"CS03322FB03"
PACK_TYPE"0402LF"
WATTAGE"1/16W"
CDS_LIB"pure_quanta"
LOCATION"R439"
$SEC"1"
CDS_SEC"1";
"B"
$PN"2"77;
"A"
$PN"1"186;
%"Q_RES"
"1","(3350,4750)","0","pure_quanta","I239";
;
MATERIAL"EMPTY"
VALUE"33.2"
TOLERANCE"1%"
PART_NUMBER"CS03322FB03"
PACK_TYPE"0402LF"
WATTAGE"1/16W"
CDS_LIB"pure_quanta"
LOCATION"R678"
$SEC"1"
CDS_SEC"1";
"B"
$PN"2"131;
"A"
$PN"1"163;
%"Q_RES"
"1","(3350,4600)","0","pure_quanta","I245";
;
VALUE"33.2"
MATERIAL"EMPTY"
TOLERANCE"1%"
PART_NUMBER"CS03322FB03"
PACK_TYPE"0402LF"
WATTAGE"1/16W"
CDS_LIB"pure_quanta"
LOCATION"R681"
$SEC"1"
CDS_SEC"1";
"B"
$PN"2"130;
"A"
$PN"1"83;
%"Q_RES"
"1","(3350,4550)","0","pure_quanta","I246";
;
VALUE"33.2"
MATERIAL"EMPTY"
TOLERANCE"1%"
PART_NUMBER"CS03322FB03"
PACK_TYPE"0402LF"
WATTAGE"1/16W"
CDS_LIB"pure_quanta"
LOCATION"R682"
$SEC"1"
CDS_SEC"1";
"B"
$PN"2"129;
"A"
$PN"1"82;
%"Q_RES"
"1","(3350,4700)","0","pure_quanta","I247";
;
VALUE"33.2"
MATERIAL"EMPTY"
TOLERANCE"1%"
PART_NUMBER"CS03322FB03"
PACK_TYPE"0402LF"
WATTAGE"1/16W"
CDS_LIB"pure_quanta"
LOCATION"R679"
$SEC"1"
CDS_SEC"1";
"B"
$PN"2"166;
"A"
$PN"1"114;
%"Q_RES"
"1","(3350,4650)","0","pure_quanta","I248";
;
VALUE"33.2"
MATERIAL"EMPTY"
TOLERANCE"1%"
PART_NUMBER"CS03322FB03"
PACK_TYPE"0402LF"
WATTAGE"1/16W"
CDS_LIB"pure_quanta"
LOCATION"R680"
$SEC"1"
CDS_SEC"1";
"B"
$PN"2"165;
"A"
$PN"1"107;
%"Q_RES"
"1","(3800,2825)","0","pure_quanta","I266";
;
MATERIAL"CHIP"
VALUE"33.2"
TOLERANCE"1%"
PART_NUMBER"CS03322FB03"
PACK_TYPE"0402LF"
WATTAGE"1/16W"
SEC_TYPE"0402LF"
CDS_LIB"pure_quanta"
LOCATION"R111"
SEC"1";
"B"
$PN"2"170;
"A"
$PN"1"69;
%"Q_RES"
"1","(2800,-600)","0","pure_quanta","I278";
;
VALUE"4.7K"
MATERIAL"CHIP"
PART_NUMBER"CS24702FB06"
PACK_TYPE"0402LF"
WATTAGE"1/16W"
TOLERANCE"1%"
SEC_TYPE"0402LF"
CDS_LIB"pure_quanta"
LOCATION"R55"
SEC"1";
"B"
$PN"2"194;
"A"
$PN"1"7;
%"Q_RES"
"1","(2800,-650)","0","pure_quanta","I279";
;
VALUE"4.7K"
MATERIAL"CHIP"
PART_NUMBER"CS24702FB06"
PACK_TYPE"0402LF"
WATTAGE"1/16W"
TOLERANCE"1%"
SEC_TYPE"0402LF"
CDS_LIB"pure_quanta"
LOCATION"R56"
SEC"1";
"B"
$PN"2"195;
"A"
$PN"1"7;
%"UNIVERSAL_GND"
"1","(-1650,-425)","0","logical_power","I28";
;
CDS_LIB"logical_power"
HDL_POWER"GND";
"A"11;
%"UNIVERSAL_POWER"
"1","(2475,-400)","0","logical_power","I282";
;
HDL_POWER"P3V3_AUX"
CDS_LIB"logical_power";
"A"7;
%"Q_RES"
"1","(3650,3025)","0","pure_quanta","I286";
;
MATERIAL"CHIP"
VALUE"33.2"
WATTAGE"1/16W"
TOLERANCE"1%"
PACK_TYPE"0402LF"
CDS_LIB"pure_quanta"
SEC_TYPE"0402LF"
PART_NUMBER"CS03322FB03"
LOCATION"R96"
SEC"1";
"B"
$PN"2"97;
"A"
$PN"1"105;
%"Q_CAP"
"1","(-1950,-150)","0","pure_quanta","I29";
;
VALUE"1UF"
VOLTAGE"25V"
MATERIAL"X6S"
PACK_TYPE"C0402"
TOLERANCE"10%"
PART_NUMBER"CH5104KEB02"
CDS_LIB"pure_quanta"
LOCATION"C30"
$SEC"1"
CDS_SEC"1";
"B"
$PN"2"11;
"A"
$PN"1"2;
%"Q_RES"
"1","(-2300,2275)","0","pure_quanta","I295";
;
VALUE"33.2"
MATERIAL"CHIP"
TOLERANCE"1%"
PART_NUMBER"CS03322FB03"
PACK_TYPE"0402LF"
WATTAGE"1/16W"
CDS_LIB"pure_quanta"
LOCATION"R840"
$SEC"1"
CDS_SEC"1";
"B"
$PN"2"146;
"A"
$PN"1"187;
%"Q_RES"
"1","(2800,-850)","0","pure_quanta","I299";
;
MATERIAL"CHIP"
VALUE"4.7K"
PART_NUMBER"CS24702FB06"
PACK_TYPE"0402LF"
WATTAGE"1/16W"
TOLERANCE"1%"
SEC_TYPE"0402LF"
CDS_LIB"pure_quanta"
LOCATION"R446"
SEC"1";
"B"
$PN"2"197;
"A"
$PN"1"7;
%"Q_RES"
"1","(-2875,-650)","0","pure_quanta","I3";
;
MATERIAL"EMPTY"
VALUE"0"
PART_NUMBER"CS00002JB13"
PACK_TYPE"0402LF"
WATTAGE"1/16W"
TOLERANCE"5%"
CDS_LIB"pure_quanta"
LOCATION"R154"
$SEC"1"
CDS_SEC"1";
"B"
$PN"2"2;
"A"
$PN"1"5;
%"Q_CAP"
"1","(-1750,-150)","0","pure_quanta","I30";
;
TOLERANCE"10%"
MATERIAL"X7R"
PACK_TYPE"0402"
VOLTAGE"25V"
VALUE"0.1UF"
PART_NUMBER"CH4104K1B00"
CDS_LIB"pure_quanta"
LOCATION"C31"
$SEC"1"
CDS_SEC"1";
"B"
$PN"2"11;
"A"
$PN"1"2;
%"Q_RES"
"1","(-1750,3225)","0","pure_quanta","I300";
;
MATERIAL"CHIP"
VALUE"33.2"
TOLERANCE"1%"
PART_NUMBER"CS03322FB03"
PACK_TYPE"0402LF"
WATTAGE"1/16W"
CDS_LIB"pure_quanta"
LOCATION"R443"
$SEC"1"
CDS_SEC"1";
"B"
$PN"2"52;
"A"
$PN"1"178;
%"Q_RES"
"1","(-1750,3275)","0","pure_quanta","I301";
;
MATERIAL"CHIP"
VALUE"33.2"
TOLERANCE"1%"
PART_NUMBER"CS03322FB03"
PACK_TYPE"0402LF"
WATTAGE"1/16W"
CDS_LIB"pure_quanta"
LOCATION"R442"
$SEC"1"
CDS_SEC"1";
"B"
$PN"2"126;
"A"
$PN"1"144;
%"Q_RES"
"1","(-1750,3075)","0","pure_quanta","I306";
;
VALUE"33.2"
MATERIAL"CHIP"
CDS_LIB"pure_quanta"
WATTAGE"1/16W"
PACK_TYPE"0402LF"
PART_NUMBER"CS03322FB03"
TOLERANCE"1%"
LOCATION"R444"
$SEC"1"
CDS_SEC"1";
"B"
$PN"2"81;
"A"
$PN"1"145;
%"Q_CAP"
"1","(-1550,-150)","0","pure_quanta","I31";
;
VOLTAGE"25V"
TOLERANCE"10%"
MATERIAL"X6S"
PACK_TYPE"C0402"
VALUE"1UF"
PART_NUMBER"CH5104KEB02"
CDS_LIB"pure_quanta"
LOCATION"C32"
$SEC"1"
CDS_SEC"1";
"B"
$PN"2"11;
"A"
$PN"1"2;
%"Q_RES"
"1","(-1775,3975)","0","pure_quanta","I312";
;
VALUE"33.2"
MATERIAL"CHIP"
TOLERANCE"1%"
PART_NUMBER"CS03322FB03"
WATTAGE"1/16W"
CDS_LIB"pure_quanta"
PACK_TYPE"0402LF"
LOCATION"R460"
$SEC"1"
CDS_SEC"1";
"B"
$PN"2"160;
"A"
$PN"1"141;
%"Q_RES"
"1","(3250,3925)","0","pure_quanta","I319";
;
MATERIAL"CHIP"
VALUE"33.2"
TOLERANCE"1%"
PART_NUMBER"CS03322FB03"
PACK_TYPE"0402LF"
WATTAGE"1/16W"
CDS_LIB"pure_quanta"
LOCATION"R469"
$SEC"1"
CDS_SEC"1";
"B"
$PN"2"128;
"A"
$PN"1"171;
%"Q_CAP"
"1","(-1350,-150)","0","pure_quanta","I32";
;
PACK_TYPE"0402"
VOLTAGE"25V"
VALUE"0.1UF"
TOLERANCE"10%"
MATERIAL"X7R"
PART_NUMBER"CH4104K1B00"
CDS_LIB"pure_quanta"
LOCATION"C33"
$SEC"1"
CDS_SEC"1";
"B"
$PN"2"11;
"A"
$PN"1"2;
%"Q_RES"
"1","(-325,-525)","0","pure_quanta","I33";
;
MATERIAL"CHIP"
TOLERANCE"1%"
VALUE"330"
WATTAGE"1/16W"
PACK_TYPE"0402LF"
PART_NUMBER"CS13302FB00"
CDS_LIB"pure_quanta"
LOCATION"R167"
$SEC"1"
CDS_SEC"1";
"B"
$PN"2"118;
"A"
$PN"1"1;
%"Q_RES"
"1","(3650,3175)","0","pure_quanta","I335";
;
MATERIAL"CHIP"
VALUE"33.2"
TOLERANCE"1%"
PART_NUMBER"CS03322FB03"
PACK_TYPE"0402LF"
WATTAGE"1/16W"
CDS_LIB"pure_quanta"
SEC_TYPE"0402LF"
LOCATION"R494"
SEC"1";
"B"
$PN"2"100;
"A"
$PN"1"172;
%"Q_RES"
"1","(3650,3125)","0","pure_quanta","I337";
;
MATERIAL"CHIP"
VALUE"0"
PART_NUMBER"CS00002JB13"
PACK_TYPE"0402LF"
WATTAGE"1/16W"
TOLERANCE"5%"
CDS_LIB"pure_quanta"
LOCATION"R637"
$SEC"1"
CDS_SEC"1";
"B"
$PN"2"99;
"A"
$PN"1"90;
%"Q_RES"
"1","(2800,-900)","0","pure_quanta","I339";
;
MATERIAL"CHIP"
VALUE"4.7K"
PART_NUMBER"CS24702FB06"
PACK_TYPE"0402LF"
WATTAGE"1/16W"
TOLERANCE"1%"
SEC_TYPE"0402LF"
CDS_LIB"pure_quanta"
LOCATION"R452"
SEC"1";
"B"
$PN"2"196;
"A"
$PN"1"7;
%"UNIVERSAL_POWER"
"1","(-575,-375)","0","logical_power","I34";
;
HDL_POWER"P3V3_AUX"
CDS_LIB"logical_power";
"A"1;
%"Q_RES"
"1","(-2275,1025)","2","pure_quanta","I340";
;
MATERIAL"CHIP"
VALUE"100K"
CDS_LIB"pure_quanta"
SEC_TYPE"0402LF"
TOLERANCE"1%"
PART_NUMBER"CS41002FB09"
WATTAGE"1/16W"
PACK_TYPE"0402LF"
LOCATION"R273"
SEC"1";
"B"
$PN"2"10;
"A"
$PN"1"14;
%"UNIVERSAL_GND"
"1","(-2400,925)","0","logical_power","I341";
;
CDS_LIB"logical_power"
HDL_POWER"GND";
"A"10;
%"Q_RES"
"1","(-1825,3675)","0","pure_quanta","I344";
;
MATERIAL"CHIP"
VALUE"33.2"
CDS_LIB"pure_quanta"
WATTAGE"1/16W"
PART_NUMBER"CS03322FB03"
TOLERANCE"1%"
PACK_TYPE"0402LF"
LOCATION"R643"
$SEC"1"
CDS_SEC"1";
"B"
$PN"2"158;
"A"
$PN"1"142;
%"Q_RES"
"1","(3800,2775)","0","pure_quanta","I349";
;
VALUE"33.2"
MATERIAL"CHIP"
TOLERANCE"1%"
PART_NUMBER"CS03322FB03"
PACK_TYPE"0402LF"
WATTAGE"1/16W"
CDS_LIB"pure_quanta"
SEC_TYPE"0402LF"
LOCATION"R407"
SEC"1";
"B"
$PN"2"169;
"A"
$PN"1"73;
%"UNIVERSAL_POWER"
"1","(-1225,250)","0","logical_power","I35";
;
HDL_POWER"P3V3_P2V5_P1V8_RVDD"
CDS_LIB"logical_power";
"A"2;
%"Q_RES"
"1","(-2175,2875)","2","pure_quanta","I350";
;
VALUE"0"
MATERIAL"CHIP"
TOLERANCE"5%"
WATTAGE"1/16W"
PACK_TYPE"0402LF"
PART_NUMBER"CS00002JB13"
CDS_LIB"pure_quanta"
LOCATION"R722"
$SEC"1"
CDS_SEC"1";
"B"
$PN"2"179;
"A"
$PN"1"49;
%"Q_RES"
"1","(3800,2575)","0","pure_quanta","I351";
;
VALUE"33.2"
MATERIAL"CHIP"
TOLERANCE"1%"
PART_NUMBER"CS03322FB03"
PACK_TYPE"0402LF"
WATTAGE"1/16W"
CDS_LIB"pure_quanta"
LOCATION"R826"
$SEC"1"
CDS_SEC"1";
"B"
$PN"2"167;
"A"
$PN"1"70;
%"Q_RES"
"1","(2750,450)","0","pure_quanta","I353";
;
MATERIAL"CHIP"
VALUE"4.7K"
PART_NUMBER"CS24702FB06"
PACK_TYPE"0402LF"
WATTAGE"1/16W"
TOLERANCE"1%"
CDS_LIB"pure_quanta"
LOCATION"R816"
$SEC"1"
CDS_SEC"1";
"B"
$PN"2"61;
"A"
$PN"1"8;
%"UNIVERSAL_POWER"
"1","(1050,100)","0","logical_power","I355";
;
HDL_POWER"P3V3_AUX"
CDS_LIB"logical_power";
"A"9;
%"Q_RES"
"1","(1300,-50)","0","pure_quanta","I356";
;
MATERIAL"CHIP"
VALUE"4.7K"
PART_NUMBER"CS24702FB06"
WATTAGE"1/16W"
TOLERANCE"1%"
CDS_LIB"pure_quanta"
PACK_TYPE"0402LF"
SEC_TYPE"0402LF"
LOCATION"R805"
SEC"1";
"B"
$PN"2"183;
"A"
$PN"1"9;
%"Q_RES"
"1","(3250,3975)","0","pure_quanta","I360";
;
VALUE"33.2"
MATERIAL"CHIP"
CDS_LIB"pure_quanta"
WATTAGE"1/16W"
PACK_TYPE"0402LF"
PART_NUMBER"CS03322FB03"
TOLERANCE"1%"
$LOCATION"R309"
CDS_LOCATION"R309"
$SEC"1"
CDS_SEC"1";
"B"
$PN"2"121;
"A"
$PN"1"115;
%"AST2600A3GP"
"2","(725,2675)","0","pure_quanta","I363";
;
PART_NUMBER"AJ026000T06"
PART_TYPE"SMLF"
MATERIAL"IC"
VALUE"AST2600A3-GP"
CDS_LIB"pure_quanta"
CDS_LMAN_SYM_OUTLINE"-1025,1700,1025,-1700"
NEEDS_NO_SIZE"TRUE"
LOCATION"U5"
$SEC"2"
CDS_SEC"2";
"GPIOI7||SIOSCI#"
$PN"A15"70;
"GPIOI5||SIOPBO#"
$PN"E16"71;
"GPIOI6||SIOPBI#"
$PN"B16"79;
"GPIOS4||TXD10"
$PN"R26"75;
"GPIOS7||RXD11"
$PN"T24"112;
"GPIOS6||TXD11"
$PN"P23"111;
"GPIOS5||RXD10"
$PN"P24"110;
"GPIOS1||MDIO1"
$PN"T25"47;
"GPIOS0||MDC1"
$PN"R23"46;
"RGMIICK"
$PN"A10"14;
"RGMII3TXD3||GPIOC5"
$PN"F22"45;
"RGMII3TXD2||GPIOC4"
$PN"G22"44;
"RGMII3TXD1||RMII3TXD1||GPIOC3"
$PN"H23"43;
"RGMII3TXD0||RMII3TXD0||GPIOC2"
$PN"H22"42;
"RGMII3TXCTL||RMII3TXEN||GPIOC1"
$PN"J22"41;
"RGMII3TXCK||RMII3RCLKO||GPIOC0"
$PN"H24"35;
"RGMII4TXD3||NRTS3||GPIOE1"
$PN"D24"34;
"RGMII4TXD2||NDTR3||GPIOE0"
$PN"D26"91;
"RGMII4TXD1||RMII4TXD1||NRI3||GPIOD7"
$PN"E25"33;
"RGMII4TXD0||RMII4TXD0||NDSR3||GPIOD6"
$PN"E24"32;
"RGMII4TXCTL||RMII4TXEN||NDCD3||GPIOD5"
$PN"E23"31;
"RGMII4TXCK||RMII4RCLKO||NCTS3||GPIOD4"
$PN"F24"30;
"RGMII4RXD3||RMII4RXER||NRTS4||GPIOE7"
$PN"B24"151;
"RGMII4RXD2||RMII4CRSDV||NDTR4||GPIOE6"
$PN"B25"19;
"RGMII4RXD1||RMII4RXD1||NRI4||GPIOE5"
$PN"B26"20;
"RGMII4RXD0||RMII4RXD0||NDSR4||GPIOE4"
$PN"C24"150;
"RGMII4RXCTL||NDCD4||GPIOE3"
$PN"C26"21;
"RGMII4RXCK||RMII4RCLKI||NCTS4||GPIOE2"
$PN"C25"149;
"RGMII3RXD3||RMII3RXER||GPIOD3"
$PN"E26"152;
"RGMII3RXD2||RMII3CRSDV||GPIOD2"
$PN"F25"16;
"RGMII3RXD1||RMII3RXD1||GPIOD1"
$PN"F26"15;
"RGMII3RXD0||RMII3RXD0||GPIOD0"
$PN"F23"17;
"RGMII3RXCTL||GPIOC7"
$PN"G24"134;
"RGMII3RXCK||RMII3RCLKI||GPIOC6"
$PN"G23"18;
"RXD5"
$PN"D8"181;
"TXD5"
$PN"C8"182;
"GPIOY3||SALT8||WDTRST4#"
$PN"AA12"105;
"GPIOY2||SALT7||WDTRST3#"
$PN"AE11"106;
"GPIOY1||SALT6||WDTRST2#"
$PN"AD12"90;
"GPIOY0||SALT5||WDTRST1#"
$PN"AF11"172;
"GPIOB7||RXD4"
$PN"J24"50;
"GPIOB6||TXD4"
$PN"H25"81;
"GPIOB5||MDIO2"
$PN"G26"51;
"GPIOB4||MDC2"
$PN"J23"88;
"GPIOB3||SALT4"
$PN"J25"52;
"GPIOB2||SALT3"
$PN"H26"126;
"GPIOB1||SALT2"
$PN"K23"76;
"GPIOB0||SALT1"
$PN"J26"53;
"GPIOX2||SPI2CS2#"
$PN"AC9"157;
"GPIOX1||SPI2CS1#"
$PN"AA9"158;
"GPIOX0||SPI2CS0#"
$PN"AE8"159;
"GPIOX7||SPI2DQ3||RXD12"
$PN"AB10"87;
"GPIOX6||SPI2DQ2||TXD12"
$PN"AF9"109;
"GPIOX5||SPI2MISO"
$PN"AD9"89;
"GPIOX4||SPI2MOSI"
$PN"AB9"86;
"GPIOX3||SPI2CK"
$PN"AF8"85;
"GPIOZ2||SPI1WP#"
$PN"AE10"54;
"GPIOZ1||SPI1ABR"
$PN"AD10"135;
"GPIOZ0||SPI1CS1#"
$PN"AC10"160;
"SPI1CS0# \B"
$PN"AD13"161;
"GPIOZ7||SPI1DQ3||RXD13"
$PN"AF10"120;
"GPIOZ6||SPI1DQ2||TXD13"
$PN"AD11"84;
"GPIOZ5||SPI1MISO"
$PN"AA11"171;
"GPIOZ4||SPI1MOSI"
$PN"AC11"115;
"GPIOZ3||SPI1CK"
$PN"AB11"108;
"GPIOY7||FWSPIWP#"
$PN"AB12"116;
"GPIOY6||FWSPIABR"
$PN"AC12"177;
"GPIOY4||FWSPIDQ2"
$PN"AE12"83;
"GPIOY5||FWSPIDQ3"
$PN"AF12"82;
"FWSPIMISO"
$PN"AB13"107;
"FWSPIMOSI"
$PN"AC14"114;
"FWSPICK"
$PN"AF13"163;
"GPIOV7||LPCSMI#"
$PN"AF15"72;
"GPIOV6||LPCPME#"
$PN"AD15"73;
"GPIOV5||LPCPD#"
$PN"AE14"69;
"GPIOV4||SIOPWRGD"
$PN"AE15"96;
"GPIOV3||SIOONCTRL#"
$PN"AC15"80;
"GPIOV2||SIOPWREQ#"
$PN"AD14"48;
"GPIOV1||SIOS5#"
$PN"AF14"174;
"GPIOV0||SIOS3#"
$PN"AB15"49;
"FWSPICS2# \B"
$PN"AC13"176;
"FWSPICS1# \B"
$PN"AA13"162;
"GPIOL4||TXD3"
$PN"C15"147;
"GPIOL5||RXD3"
$PN"F15"148;
"GPION7||RXD2"
$PN"M26"92;
"GPION6||TXD2"
$PN"N26"93;
"GPION5||NRTS2"
$PN"M23"94;
"GPION4||NDTR2"
$PN"P26"95;
"GPION3||NRI2"
$PN"N24"27;
"GPION2||NDSR2"
$PN"N25"26;
"GPION1||NDCD2"
$PN"N23"103;
"GPION0||NCTS2"
$PN"P25"104;
"GPIOM7||RXD1"
$PN"D13"22;
"GPIOM6||TXD1"
$PN"C13"23;
"GPIOM5||NRTS1"
$PN"C12"24;
"GPIOM4||NDTR1"
$PN"B12"146;
"GPIOM3||NRI1"
$PN"E14"77;
"GPIOM2||NDSR1"
$PN"A12"25;
"GPIOM1||NDCD1"
$PN"B13"78;
"GPIOM0||NCTS1"
$PN"D14"173;
"FWSPICS0# \B"
$PN"AB14"175;
%"Q_RES"
"1","(-1775,2775)","0","pure_quanta","I365";
;
MATERIAL"CHIP"
VALUE"33.2"
CDS_LIB"pure_quanta"
WATTAGE"1/16W"
PACK_TYPE"0402LF"
PART_NUMBER"CS03322FB03"
TOLERANCE"1%"
LOCATION"R461"
$SEC"1"
CDS_SEC"1";
"B"
$PN"2"48;
"A"
$PN"1"154;
%"Q_RES"
"1","(-1775,4125)","0","pure_quanta","I373";
;
VALUE"33.2"
MATERIAL"CHIP"
PACK_TYPE"0402LF"
CDS_LIB"pure_quanta"
WATTAGE"1/16W"
PART_NUMBER"CS03322FB03"
TOLERANCE"1%"
$LOCATION"R402"
CDS_LOCATION"R402"
$SEC"1"
CDS_SEC"1";
"B"
$PN"2"116;
"A"
$PN"1"117;
%"Q_RES"
"1","(-1775,4175)","0","pure_quanta","I374";
;
VALUE"33.2"
MATERIAL"CHIP"
PACK_TYPE"0402LF"
CDS_LIB"pure_quanta"
WATTAGE"1/16W"
PART_NUMBER"CS03322FB03"
TOLERANCE"1%"
$LOCATION"R401"
CDS_LOCATION"R401"
$SEC"1"
CDS_SEC"1";
"B"
$PN"2"177;
"A"
$PN"1"140;
%"Q_RES"
"1","(3275,1375)","0","pure_quanta","I381";
;
VALUE"33.2"
MATERIAL"CHIP"
PACK_TYPE"0402LF"
WATTAGE"1/16W"
CDS_LIB"pure_quanta"
PART_NUMBER"CS03322FB03"
TOLERANCE"1%"
LOCATION"R121"
$SEC"1"
CDS_SEC"1";
"B"
$PN"2"55;
"A"
$PN"1"41;
%"Q_RES"
"1","(3275,1225)","0","pure_quanta","I382";
;
VALUE"33.2"
MATERIAL"CHIP"
PACK_TYPE"0402LF"
WATTAGE"1/16W"
CDS_LIB"pure_quanta"
PART_NUMBER"CS03322FB03"
TOLERANCE"1%"
LOCATION"R60"
$SEC"1"
CDS_SEC"1";
"B"
$PN"2"57;
"A"
$PN"1"44;
%"Q_RES"
"1","(3275,1275)","0","pure_quanta","I383";
;
VALUE"33.2"
MATERIAL"CHIP"
TOLERANCE"1%"
PART_NUMBER"CS03322FB03"
CDS_LIB"pure_quanta"
WATTAGE"1/16W"
PACK_TYPE"0402LF"
LOCATION"R688"
$SEC"1"
CDS_SEC"1";
"B"
$PN"2"56;
"A"
$PN"1"43;
%"Q_RES"
"1","(3275,1325)","0","pure_quanta","I384";
;
VALUE"33.2"
MATERIAL"CHIP"
PACK_TYPE"0402LF"
WATTAGE"1/16W"
CDS_LIB"pure_quanta"
PART_NUMBER"CS03322FB03"
TOLERANCE"1%"
LOCATION"R242"
$SEC"1"
CDS_SEC"1";
"B"
$PN"2"67;
"A"
$PN"1"42;
%"Q_RES"
"1","(-2175,1375)","0","pure_quanta","I398";
;
VALUE"33.2"
MATERIAL"EMPTY"
TOLERANCE"1%"
PART_NUMBER"CS03322FB03"
CDS_LIB"pure_quanta"
WATTAGE"1/16W"
PACK_TYPE"0402LF"
LOCATION"R689"
$SEC"1"
CDS_SEC"1";
"B"
$PN"2"134;
"A"
$PN"1"119;
%"Q_RES"
"1","(-2200,1225)","0","pure_quanta","I399";
;
MATERIAL"CHIP"
VALUE"33.2"
TOLERANCE"1%"
PART_NUMBER"CS03322FB03"
CDS_LIB"pure_quanta"
WATTAGE"1/16W"
PACK_TYPE"0402LF"
LOCATION"R122"
$SEC"1"
CDS_SEC"1";
"B"
$PN"2"16;
"A"
$PN"1"133;
%"Q_RES"
"1","(-2800,-300)","0","pure_quanta","I4";
;
MATERIAL"EMPTY"
VALUE"0"
PART_NUMBER"CS00002JB13"
PACK_TYPE"0402LF"
WATTAGE"1/16W"
TOLERANCE"5%"
CDS_LIB"pure_quanta"
LOCATION"R156"
$SEC"1"
CDS_SEC"1";
"B"
$PN"2"2;
"A"
$PN"1"4;
%"Q_RES"
"1","(-2200,1175)","0","pure_quanta","I400";
;
MATERIAL"CHIP"
VALUE"33.2"
PACK_TYPE"0402LF"
WATTAGE"1/16W"
CDS_LIB"pure_quanta"
PART_NUMBER"CS03322FB03"
TOLERANCE"1%"
LOCATION"R760"
$SEC"1"
CDS_SEC"1";
"B"
$PN"2"152;
"A"
$PN"1"132;
%"Q_RES"
"1","(-2200,1775)","0","pure_quanta","I402";
;
VALUE"33.2"
MATERIAL"CHIP"
TOLERANCE"1%"
PART_NUMBER"CS03322FB03"
CDS_LIB"pure_quanta"
WATTAGE"1/16W"
PACK_TYPE"0402LF"
LOCATION"R763"
$SEC"1"
CDS_SEC"1";
"B"
$PN"2"21;
"A"
$PN"1"192;
%"Q_RES"
"1","(3250,3875)","0","pure_quanta","I407";
;
VALUE"33.2"
MATERIAL"CHIP"
PACK_TYPE"0402LF"
WATTAGE"1/16W"
CDS_LIB"pure_quanta"
PART_NUMBER"CS03322FB03"
TOLERANCE"1%"
LOCATION"R458"
$SEC"1"
CDS_SEC"1";
"B"
$PN"2"127;
"A"
$PN"1"84;
%"Q_RES"
"1","(3650,3275)","0","pure_quanta","I419";
;
VALUE"33.2"
MATERIAL"CHIP"
TOLERANCE"1%"
PART_NUMBER"CS03322FB03"
PACK_TYPE"0402LF"
WATTAGE"1/16W"
CDS_LIB"pure_quanta"
SEC_TYPE"0402LF"
LOCATION"R70"
SEC"1";
"B"
$PN"2"102;
"A"
$PN"1"111;
%"Q_RES"
"1","(3650,3225)","0","pure_quanta","I421";
;
VALUE"33.2"
MATERIAL"CHIP"
SEC_TYPE"0402LF"
CDS_LIB"pure_quanta"
WATTAGE"1/16W"
PACK_TYPE"0402LF"
PART_NUMBER"CS03322FB03"
TOLERANCE"1%"
LOCATION"R65"
SEC"1";
"B"
$PN"2"101;
"A"
$PN"1"112;
%"Q_RES"
"1","(3150,1575)","0","pure_quanta","I427";
;
VALUE"33.2"
MATERIAL"CHIP"
TOLERANCE"1%"
PART_NUMBER"CS03322FB03"
PACK_TYPE"0402LF"
WATTAGE"1/16W"
CDS_LIB"pure_quanta"
LOCATION"R112"
$SEC"1"
CDS_SEC"1";
"B"
$PN"2"36;
"A"
$PN"1"34;
%"Q_RES"
"1","(3150,1625)","0","pure_quanta","I430";
;
MATERIAL"CHIP"
VALUE"33.2"
TOLERANCE"1%"
PART_NUMBER"CS03322FB03"
PACK_TYPE"0402LF"
WATTAGE"1/16W"
CDS_LIB"pure_quanta"
LOCATION"R405"
$SEC"1"
CDS_SEC"1";
"B"
$PN"2"37;
"A"
$PN"1"91;
%"Q_RES"
"1","(3800,2625)","0","pure_quanta","I431";
;
MATERIAL"CHIP"
VALUE"33.2"
TOLERANCE"1%"
PART_NUMBER"CS03322FB03"
PACK_TYPE"0402LF"
WATTAGE"1/16W"
CDS_LIB"pure_quanta"
LOCATION"R466"
$SEC"1"
CDS_SEC"1";
"B"
$PN"2"168;
"A"
$PN"1"71;
%"Q_RES"
"1","(3650,3075)","0","pure_quanta","I432";
;
VALUE"33.2"
MATERIAL"CHIP"
CDS_LIB"pure_quanta"
WATTAGE"1/16W"
PACK_TYPE"0402LF"
PART_NUMBER"CS03322FB03"
TOLERANCE"1%"
LOCATION"R465"
$SEC"1"
CDS_SEC"1";
"B"
$PN"2"98;
"A"
$PN"1"106;
%"74LVC1G66GV"
"1","(-1925,4775)","0","pure_quanta","I435";
;
VALUE"74LVC1G66GV"
PART_NUMBER"AL001G66000"
MATERIAL"IC"
PART_TYPE"SMLF"
CDS_LMAN_SYM_OUTLINE"-150,150,150,-150"
PIN_NAMES_ROTATE"True"
CDS_LIB"pure_quanta"
$LOCATION"U28"
CDS_LOCATION"U28"
$SEC"1"
CDS_SEC"1";
"VCC"
$PN"5"6;
"E"
$PN"4"138;
"GND"
$PN"3"13;
"Z"
$PN"2"124;
"Y"
$PN"1"137;
%"UNIVERSAL_GND"
"1","(-2325,4550)","0","logical_power","I439";
;
HDL_POWER"GND"
CDS_LIB"logical_power";
"A"13;
%"Q_CAP"
"1","(-1175,5025)","2","pure_quanta","I440";
;
VOLTAGE"25V"
PACK_TYPE"0402"
PART_NUMBER"CH4104K1B00"
MATERIAL"X7R"
TOLERANCE"10%"
VALUE"0.1UF"
CDS_LIB"pure_quanta"
$LOCATION"C180"
CDS_LOCATION"C180"
$SEC"1"
CDS_SEC"1";
"B"
$PN"2"12;
"A"
$PN"1"6;
%"VCCAUX15"
"1","(-1600,5200)","0","logical_power","I441";
;
HDL_POWER"P3V3_LDO"
CDS_LIB"logical_power";
"A"6;
%"UNIVERSAL_GND"
"1","(-1175,4850)","0","logical_power","I442";
;
CDS_LIB"logical_power"
HDL_POWER"GND";
"A"12;
%"Q_RES"
"2","(-3350,4625)","0","pure_quanta","I447";
;
VALUE"0"
MATERIAL"CHIP"
PART_NUMBER"CS00002JB13"
CDS_LIB"pure_quanta"
PACK_TYPE"0402LF"
WATTAGE"1/16W"
TOLERANCE"5%"
LOCATION"R392"
$SEC"1"
CDS_SEC"1";
"A"
$PN"1"124;
"B"
$PN"2"155;
%"Q_RES"
"2","(-775,4625)","0","pure_quanta","I448";
;
VALUE"0"
MATERIAL"CHIP"
PART_NUMBER"CS00002JB13"
CDS_LIB"pure_quanta"
TOLERANCE"5%"
WATTAGE"1/16W"
PACK_TYPE"0402LF"
$LOCATION"R395"
CDS_LOCATION"R395"
$SEC"1"
CDS_SEC"1";
"A"
$PN"1"138;
"B"
$PN"2"139;
%"Q_RES"
"1","(3250,4025)","0","pure_quanta","I449";
;
PART_NUMBER"CS09092FB15"
VALUE"90.9"
MATERIAL"CHIP"
CDS_LIB"pure_quanta"
TOLERANCE"1%"
WATTAGE"1/16W"
PACK_TYPE"0402LF"
LOCATION"R468"
$SEC"1"
CDS_SEC"1";
"B"
$PN"2"122;
"A"
$PN"1"108;
%"Q_RES"
"1","(3150,1775)","0","pure_quanta","I451";
;
PART_NUMBER"CS02202FB02"
MATERIAL"CHIP"
VALUE"22"
TOLERANCE"1%"
PACK_TYPE"0402LF"
WATTAGE"1/16W"
CDS_LIB"pure_quanta"
LOCATION"R171"
$SEC"1"
CDS_SEC"1";
"B"
$PN"2"40;
"A"
$PN"1"31;
%"Q_RES"
"1","(3150,1725)","0","pure_quanta","I452";
;
MATERIAL"CHIP"
VALUE"22"
WATTAGE"1/16W"
PACK_TYPE"0402LF"
TOLERANCE"1%"
CDS_LIB"pure_quanta"
PART_NUMBER"CS02202FB02"
LOCATION"R172"
$SEC"1"
CDS_SEC"1";
"B"
$PN"2"39;
"A"
$PN"1"32;
%"Q_RES"
"1","(3150,1675)","0","pure_quanta","I453";
;
MATERIAL"CHIP"
VALUE"22"
WATTAGE"1/16W"
PACK_TYPE"0402LF"
TOLERANCE"1%"
CDS_LIB"pure_quanta"
PART_NUMBER"CS02202FB02"
LOCATION"R173"
$SEC"1"
CDS_SEC"1";
"B"
$PN"2"38;
"A"
$PN"1"33;
%"Q_LED"
"1","(825,-525)","0","pure_quanta","I46";
;
MANUF_PN"19-213/GVC-AMNB/3T"
COLOR"LED_GREEN"
MATERIAL"IC"
PART_NUMBER"BEGR0278Z00"
PACK_TYPE"SMLF"
CDS_LIB"pure_quanta"
NEEDS_NO_SIZE"TRUE"
LOCATION"D8"
$SEC"1"
CDS_SEC"1";
"A"
$PN"A"118;
"C"
$PN"C"183;
%"Q_RES"
"1","(-2800,0)","0","pure_quanta","I5";
;
VALUE"0"
TOLERANCE"5%"
PACK_TYPE"0402LF"
MATERIAL"CHIP"
WATTAGE"1/16W"
PART_NUMBER"CS00002JB13"
CDS_LIB"pure_quanta"
LOCATION"R155"
$SEC"1"
CDS_SEC"1";
"B"
$PN"2"2;
"A"
$PN"1"3;
%"Q_RES"
"1","(-1750,3025)","0","pure_quanta","I50";
;
VALUE"33.2"
MATERIAL"CHIP"
TOLERANCE"1%"
PART_NUMBER"CS03322FB03"
PACK_TYPE"0402LF"
WATTAGE"1/16W"
CDS_LIB"pure_quanta"
LOCATION"R166"
$SEC"1"
CDS_SEC"1";
"B"
$PN"2"50;
"A"
$PN"1"125;
%"UNIVERSAL_POWER"
"1","(-3175,250)","0","logical_power","I6";
;
HDL_POWER"P3V3_AUX"
CDS_LIB"logical_power";
"A"3;
%"Q_RES"
"1","(2875,2025)","0","pure_quanta","I67";
;
VALUE"33.2"
MATERIAL"CHIP"
TOLERANCE"1%"
PART_NUMBER"CS03322FB03"
PACK_TYPE"0402LF"
WATTAGE"1/16W"
CDS_LIB"pure_quanta"
LOCATION"R170"
$SEC"1"
CDS_SEC"1";
"B"
$PN"2"29;
"A"
$PN"1"182;
%"Q_RES"
"1","(3650,3325)","0","pure_quanta","I87";
;
VALUE"33.2"
MATERIAL"CHIP"
SEC_TYPE"0402LF"
CDS_LIB"pure_quanta"
WATTAGE"1/16W"
PACK_TYPE"0402LF"
PART_NUMBER"CS03322FB03"
TOLERANCE"1%"
LOCATION"R177"
SEC"1";
"B"
$PN"2"74;
"A"
$PN"1"110;
%"Q_RES"
"1","(3350,4325)","0","pure_quanta","I94";
;
MATERIAL"CHIP"
VALUE"33.2"
TOLERANCE"1%"
PART_NUMBER"CS03322FB03"
PACK_TYPE"0402LF"
WATTAGE"1/16W"
CDS_LIB"pure_quanta"
LOCATION"R178"
$SEC"1"
CDS_SEC"1";
"B"
$PN"2"113;
"A"
$PN"1"163;
%"Q_RES"
"1","(3350,4275)","0","pure_quanta","I95";
;
VALUE"33.2"
MATERIAL"CHIP"
TOLERANCE"1%"
PART_NUMBER"CS03322FB03"
PACK_TYPE"0402LF"
WATTAGE"1/16W"
CDS_LIB"pure_quanta"
LOCATION"R179"
$SEC"1"
CDS_SEC"1";
"B"
$PN"2"123;
"A"
$PN"1"114;
%"Q_RES"
"1","(3350,4225)","0","pure_quanta","I96";
;
MATERIAL"CHIP"
VALUE"33.2"
TOLERANCE"1%"
PART_NUMBER"CS03322FB03"
PACK_TYPE"0402LF"
WATTAGE"1/16W"
CDS_LIB"pure_quanta"
LOCATION"R180"
$SEC"1"
CDS_SEC"1";
"B"
$PN"2"164;
"A"
$PN"1"107;
END.
